(kicad_pcb
	(version 20221018)
	(generator pcbnew)
	(general
    (thickness 1.62)
  )
	(paper "A4")
	(title_block
    (title "ECP5 - Datacenter Secure Control Module (DC-SCM)")
    (date "2024-07-01")
    (rev "1.2.1")
		(comment 9 "footprints 126-133 of 506")
	)
	(layers
    (0 "F.Cu" signal)
    (1 "In1.Cu" power)
    (2 "In2.Cu" signal)
    (3 "In3.Cu" power)
    (4 "In4.Cu" power)
    (5 "In5.Cu" signal)
    (6 "In6.Cu" power)
    (31 "B.Cu" signal)
    (32 "B.Adhes" user "B.Adhesive")
    (33 "F.Adhes" user "F.Adhesive")
    (34 "B.Paste" user)
    (35 "F.Paste" user)
    (36 "B.SilkS" user "B.Silkscreen")
    (37 "F.SilkS" user "F.Silkscreen")
    (38 "B.Mask" user)
    (39 "F.Mask" user)
    (40 "Dwgs.User" user "User.Drawings")
    (41 "Cmts.User" user "User.Comments")
    (42 "Eco1.User" user "User.Eco1")
    (43 "Eco2.User" user "User.Eco2")
    (44 "Edge.Cuts" user)
    (45 "Margin" user)
    (46 "B.CrtYd" user "B.Courtyard")
    (47 "F.CrtYd" user "F.Courtyard")
    (48 "B.Fab" user)
    (49 "F.Fab" user)
  )
	(footprint "antmicro-footprints:R_0402_1005Metric" (layer "F.Cu")
    (at 84.6 88.7 180)
    (descr "Resistor SMD 0402")
    (tags "resistor SMD 0402")
    (property "Author" "Antmicro")
    (property "License" "Apache-2.0")
    (property "MPN" "CR0402-FX-4533GLF")
    (property "Manufacturer" "Bourns")
    (property "Public" "False")
    (property "Sheetfile" "power-supply.kicad_sch")
    (property "Sheetname" "Power supply")
    (property "Tolerance" "1%")
    (property "Val" "453k")
    (property "ki_description" "SMD Chip Resistor")
    (property "ki_keywords" "0402, SMT, RESISTOR, PASSIVE")
    (attr smd)
    (fp_text reference "R114" (at -0.11 -1.885) (layer "F.SilkS")
        (effects (font (size 0.7 0.7) (thickness 0.127)))
    )
    (fp_text value "R_453k_0402" (at 0 1.17) (layer "F.Fab")
        (effects (font (size 1 1) (thickness 0.15)))
    )
    (fp_text user "${REFERENCE}" (at 0 0) (layer "F.Fab")
        (effects (font (size 0.25 0.25) (thickness 0.04)))
    )
    (fp_text user "Author: Antmicro" (at -0.95 4.169 180) (layer "F.Fab") hide
        (effects (font (size 0.7 0.7) (thickness 0.15)) (justify left bottom))
    )
    (fp_text user "License: Apache-2.0" (at -0.95 5.169 180) (layer "F.Fab") hide
        (effects (font (size 0.7 0.7) (thickness 0.15)) (justify left bottom))
    )
    (fp_rect (start -0.925 -0.47) (end 0.925 0.47)
      (stroke (width 0.05) (type default)) (fill none) (layer "F.CrtYd"))
    (fp_rect (start -0.5 -0.25) (end 0.5 0.25)
      (stroke (width 0.15) (type solid)) (fill none) (layer "F.Fab"))
    (pad "1" smd roundrect (at -0.48 0 180) (size 0.59 0.64) (layers "F.Cu" "F.Paste" "F.Mask") (roundrect_rratio 0.25)
      (net 355 "Net-(C118-Pad2)") (pintype "passive"))
    (pad "2" smd roundrect (at 0.48 0 180) (size 0.59 0.64) (layers "F.Cu" "F.Paste" "F.Mask") (roundrect_rratio 0.25)
      (net 291 "Net-(U17-FB)") (pintype "passive"))
  )
	(footprint "antmicro-footprints:QFN-8_2x1.5mm" (layer "F.Cu")
    (at 83.1 86.15 90)
    (property "Author" "Antmicro")
    (property "License" "Apache-2.0")
    (property "MPN" "TPS62823DLCT")
    (property "Manufacturer" "Texas Instruments")
    (property "Sheetfile" "power-supply.kicad_sch")
    (property "Sheetname" "Power supply")
    (property "ki_description" "DC/DC converter")
    (property "ki_keywords" "SMT, PMIC, IC, SWITCHING, VOLTAGE, REGULATOR, DC-DC")
    (attr smd)
    (fp_text reference "U17" (at 1.515 -1.55 90) (layer "F.SilkS")
        (effects (font (size 0.7 0.7) (thickness 0.127)))
    )
    (fp_text value "TPS62823DLCT" (at 0 2.075 90) (layer "F.Fab")
        (effects (font (size 1 1) (thickness 0.15)))
    )
    (fp_text user "License: Apache-2.0" (at -1.651 6.475 90) (layer "F.Fab") hide
        (effects (font (size 0.7 0.7) (thickness 0.15)) (justify left bottom))
    )
    (fp_text user "${REFERENCE}" (at 0 0 90) (layer "F.Fab")
        (effects (font (size 0.5 0.5) (thickness 0.075)))
    )
    (fp_text user "Author: Antmicro" (at -1.651 5.275 90) (layer "F.Fab") hide
        (effects (font (size 0.7 0.7) (thickness 0.15)) (justify left bottom))
    )
    (fp_line (start -0.9 1.05) (end 0.9 1.05)
      (stroke (width 0.15) (type solid)) (layer "F.SilkS"))
    (fp_line (start -0.25 -1.05) (end 0.9 -1.05)
      (stroke (width 0.15) (type solid)) (layer "F.SilkS"))
    (fp_circle (center -0.9 -1.05) (end -0.849 -1.05)
      (stroke (width 0.15) (type solid)) (fill solid) (layer "F.SilkS"))
    (fp_rect (start -1.1 -1.25) (end 1.1 1.25)
      (stroke (width 0.05) (type solid)) (fill none) (layer "F.CrtYd"))
    (fp_line (start -1 -0.5) (end -0.5 -1)
      (stroke (width 0.15) (type solid)) (layer "F.Fab"))
    (fp_line (start -1 0.998) (end -1 -0.5)
      (stroke (width 0.15) (type solid)) (layer "F.Fab"))
    (fp_line (start -0.5 -1) (end 0.998 -1)
      (stroke (width 0.15) (type solid)) (layer "F.Fab"))
    (fp_line (start 0.998 -1) (end 0.998 0.998)
      (stroke (width 0.15) (type solid)) (layer "F.Fab"))
    (fp_line (start 0.998 0.998) (end -1 0.998)
      (stroke (width 0.15) (type solid)) (layer "F.Fab"))
    (pad "1" smd rect (at -0.677 -0.75 90) (size 0.55 0.25) (layers "F.Cu" "F.Paste" "F.Mask")
      (net 231 "/Power supply/VCCIO_EN") (pinfunction "EN") (pintype "input"))
    (pad "2" smd rect (at -0.677 -0.25 90) (size 0.55 0.25) (layers "F.Cu" "F.Paste" "F.Mask")
      (net 291 "Net-(U17-FB)") (pinfunction "FB") (pintype "bidirectional"))
    (pad "3" smd rect (at -0.677 0.248 90) (size 0.55 0.25) (layers "F.Cu" "F.Paste" "F.Mask")
      (net 1 "GND") (pinfunction "AGND") (pintype "power_in"))
    (pad "4" smd rect (at -0.677 0.748 90) (size 0.55 0.25) (layers "F.Cu" "F.Paste" "F.Mask")
      (net 543 "unconnected-(U17-NC-Pad4)") (pinfunction "NC") (pintype "no_connect"))
    (pad "5" smd rect (at 0.675 0.748 90) (size 0.55 0.25) (layers "F.Cu" "F.Paste" "F.Mask")
      (net 1 "GND") (pinfunction "PGND") (pintype "power_in"))
    (pad "6" smd rect (at 0.675 0.248 90) (size 0.55 0.25) (layers "F.Cu" "F.Paste" "F.Mask")
      (net 389 "Net-(U17-SW)") (pinfunction "SW") (pintype "bidirectional"))
    (pad "7" smd rect (at 0.675 -0.25 90) (size 0.55 0.25) (layers "F.Cu" "F.Paste" "F.Mask")
      (net 11 "VCC5V0") (pinfunction "VIN") (pintype "power_in"))
    (pad "8" smd rect (at 0.675 -0.75 90) (size 0.55 0.25) (layers "F.Cu" "F.Paste" "F.Mask")
      (net 222 "/Power supply/3V3_PG") (pinfunction "PG") (pintype "output"))
  )
	(footprint "antmicro-footprints:R_0603_1608Metric" (layer "F.Cu")
    (at 80.65 87.2 90)
    (descr "Resistor SMD 0603")
    (tags "resistor SMD 0603")
    (property "Author" "Antmicro")
    (property "Current" "1A")
    (property "License" "Apache-2.0")
    (property "MPN" "CR0603-J/-000ELF")
    (property "Manufacturer" "Bourns")
    (property "Public" "False")
    (property "Sheetfile" "power-supply.kicad_sch")
    (property "Sheetname" "Power supply")
    (property "Tolerance" "")
    (property "Val" "0R")
    (property "ki_description" "Zero Ohm Resistor, Jumper, 0603 [1608 Metric], Thick Film, 100 mW, 1 A, Surface Mount Device, CR")
    (property "ki_keywords" "0603, SMT, RESISTOR, PASSIVE")
    (attr smd)
    (fp_text reference "R143" (at -2.425 -0.01 90) (layer "F.SilkS")
        (effects (font (size 0.7 0.7) (thickness 0.127)))
    )
    (fp_text value "R_0R_0603" (at 0 1.9 90) (layer "F.Fab")
        (effects (font (size 1 1) (thickness 0.15)))
    )
    (fp_text user "${REFERENCE}" (at -1.25 3.898 90) (layer "F.Fab") hide
        (effects (font (size 0.7 0.7) (thickness 0.15)) (justify left bottom))
    )
    (fp_text user "Author: Antmicro" (at -1.25 4.9 90) (layer "F.Fab") hide
        (effects (font (size 0.7 0.7) (thickness 0.15)) (justify left bottom))
    )
    (fp_text user "License: Apache-2.0" (at -1.25 5.9 90) (layer "F.Fab") hide
        (effects (font (size 0.7 0.7) (thickness 0.15)) (justify left bottom))
    )
    (fp_line (start -0.15 -0.4) (end 0.15 -0.4)
      (stroke (width 0.15) (type solid)) (layer "F.SilkS"))
    (fp_line (start -0.15 0.4) (end 0.15 0.4)
      (stroke (width 0.15) (type solid)) (layer "F.SilkS"))
    (fp_rect (start -1.25 -0.65) (end 1.25 0.65)
      (stroke (width 0.05) (type solid)) (fill none) (layer "F.CrtYd"))
    (fp_rect (start -0.8 -0.4) (end 0.8 0.4)
      (stroke (width 0.15) (type solid)) (fill none) (layer "F.Fab"))
    (pad "1" smd roundrect (at -0.7 0 90) (size 0.8 1) (layers "F.Cu" "F.Paste" "F.Mask") (roundrect_rratio 0.2)
      (net 3 "VCC1V35") (pintype "passive"))
    (pad "2" smd roundrect (at 0.7 0 90) (size 0.8 1) (layers "F.Cu" "F.Paste" "F.Mask") (roundrect_rratio 0.2)
      (net 357 "Net-(C120-Pad2)") (pintype "passive"))
  )
	(footprint "antmicro-footprints:C_0402_1005Metric" (layer "F.Cu")
    (at 89.35 83.945 180)
    (descr "Capacitor SMD 0402")
    (tags "capacitor SMD 0402")
    (property "Author" "Antmicro")
    (property "Dielectric" "")
    (property "License" "Apache-2.0")
    (property "MPN" "CC0402MRX5R5BB106")
    (property "Manufacturer" "YAGEO")
    (property "Public" "False")
    (property "Sheetfile" "power-supply.kicad_sch")
    (property "Sheetname" "Power supply")
    (property "Val" "10u")
    (property "Voltage" "")
    (property "ki_description" "SMD Multilayer Ceramic Capacitor, 10 µF, 6.3 V, 0402 [1005 Metric], ± 20%, X5R, CC Series")
    (property "ki_keywords" "0402, SMT, CAPACITOR, PASSIVE, MLCC, CERAMIC")
    (attr smd)
    (fp_text reference "C113" (at 1.41 0.43 90) (layer "F.SilkS")
        (effects (font (size 0.7 0.7) (thickness 0.127)))
    )
    (fp_text value "C_10u_0402" (at 0 1.17) (layer "F.Fab")
        (effects (font (size 1 1) (thickness 0.15)))
    )
    (fp_text user "${REFERENCE}" (at 0 0) (layer "F.Fab")
        (effects (font (size 0.25 0.25) (thickness 0.04)))
    )
    (fp_text user "Author: Antmicro" (at -0.939 3.399 180) (layer "F.Fab") hide
        (effects (font (size 0.7 0.7) (thickness 0.15)) (justify left bottom))
    )
    (fp_text user "License: Apache-2.0" (at -0.939 5.799 180) (layer "F.Fab") hide
        (effects (font (size 0.7 0.7) (thickness 0.15)) (justify left bottom))
    )
    (fp_rect (start -0.925 -0.47) (end 0.925 0.47)
      (stroke (width 0.05) (type default)) (fill none) (layer "F.CrtYd"))
    (fp_line (start -0.494 -0.25) (end 0.504 -0.25)
      (stroke (width 0.15) (type solid)) (layer "F.Fab"))
    (fp_line (start -0.494 0.248) (end -0.494 -0.25)
      (stroke (width 0.15) (type solid)) (layer "F.Fab"))
    (fp_line (start 0.504 -0.25) (end 0.504 0.248)
      (stroke (width 0.15) (type solid)) (layer "F.Fab"))
    (fp_line (start 0.504 0.248) (end -0.494 0.248)
      (stroke (width 0.15) (type solid)) (layer "F.Fab"))
    (pad "1" smd roundrect (at -0.48 0 180) (size 0.59 0.64) (layers "F.Cu" "F.Paste" "F.Mask") (roundrect_rratio 0.25)
      (net 1 "GND") (pintype "passive"))
    (pad "2" smd roundrect (at 0.48 0 180) (size 0.59 0.64) (layers "F.Cu" "F.Paste" "F.Mask") (roundrect_rratio 0.25)
      (net 11 "VCC5V0") (pintype "passive"))
  )
	(footprint "antmicro-footprints:C_0402_1005Metric" (layer "F.Cu")
    (at 118.239056 81.415 180)
    (descr "Capacitor SMD 0402")
    (tags "capacitor SMD 0402")
    (property "Author" "Antmicro")
    (property "Dielectric" "")
    (property "License" "Apache-2.0")
    (property "MPN" "CC0402MRX5R5BB106")
    (property "Manufacturer" "YAGEO")
    (property "Public" "False")
    (property "Sheetfile" "power-supply.kicad_sch")
    (property "Sheetname" "Power supply")
    (property "Val" "10u")
    (property "Voltage" "")
    (property "ki_description" "SMD Multilayer Ceramic Capacitor, 10 µF, 6.3 V, 0402 [1005 Metric], ± 20%, X5R, CC Series")
    (property "ki_keywords" "0402, SMT, CAPACITOR, PASSIVE, MLCC, CERAMIC")
    (attr smd)
    (fp_text reference "C115" (at 3.099056 -0.05) (layer "F.SilkS")
        (effects (font (size 0.7 0.7) (thickness 0.127)))
    )
    (fp_text value "C_10u_0402" (at 0 1.17) (layer "F.Fab")
        (effects (font (size 1 1) (thickness 0.15)))
    )
    (fp_text user "License: Apache-2.0" (at -0.939 5.799 180) (layer "F.Fab") hide
        (effects (font (size 0.7 0.7) (thickness 0.15)) (justify left bottom))
    )
    (fp_text user "${REFERENCE}" (at 0 0 90) (layer "F.Fab")
        (effects (font (size 0.25 0.25) (thickness 0.04)))
    )
    (fp_text user "Author: Antmicro" (at -0.939 3.399 180) (layer "F.Fab") hide
        (effects (font (size 0.7 0.7) (thickness 0.15)) (justify left bottom))
    )
    (fp_rect (start -0.925 -0.47) (end 0.925 0.47)
      (stroke (width 0.05) (type default)) (fill none) (layer "F.CrtYd"))
    (fp_line (start -0.494 -0.25) (end 0.504 -0.25)
      (stroke (width 0.15) (type solid)) (layer "F.Fab"))
    (fp_line (start -0.494 0.248) (end -0.494 -0.25)
      (stroke (width 0.15) (type solid)) (layer "F.Fab"))
    (fp_line (start 0.504 -0.25) (end 0.504 0.248)
      (stroke (width 0.15) (type solid)) (layer "F.Fab"))
    (fp_line (start 0.504 0.248) (end -0.494 0.248)
      (stroke (width 0.15) (type solid)) (layer "F.Fab"))
    (pad "1" smd roundrect (at -0.48 0 180) (size 0.59 0.64) (layers "F.Cu" "F.Paste" "F.Mask") (roundrect_rratio 0.25)
      (net 1 "GND") (pintype "passive"))
    (pad "2" smd roundrect (at 0.48 0 180) (size 0.59 0.64) (layers "F.Cu" "F.Paste" "F.Mask") (roundrect_rratio 0.25)
      (net 11 "VCC5V0") (pintype "passive"))
  )
	(footprint "antmicro-footprints:C_0402_1005Metric" (layer "F.Cu")
    (at 80.05 85.1)
    (descr "Capacitor SMD 0402")
    (tags "capacitor SMD 0402")
    (property "Author" "Antmicro")
    (property "Dielectric" "")
    (property "License" "Apache-2.0")
    (property "MPN" "CC0402MRX5R5BB106")
    (property "Manufacturer" "YAGEO")
    (property "Public" "False")
    (property "Sheetfile" "power-supply.kicad_sch")
    (property "Sheetname" "Power supply")
    (property "Val" "10u")
    (property "Voltage" "")
    (property "ki_description" "SMD Multilayer Ceramic Capacitor, 10 µF, 6.3 V, 0402 [1005 Metric], ± 20%, X5R, CC Series")
    (property "ki_keywords" "0402, SMT, CAPACITOR, PASSIVE, MLCC, CERAMIC")
    (attr smd)
    (fp_text reference "C130" (at -0.44 1.865 -90) (layer "F.SilkS")
        (effects (font (size 0.7 0.7) (thickness 0.127)))
    )
    (fp_text value "C_10u_0402" (at 0 1.17) (layer "F.Fab")
        (effects (font (size 1 1) (thickness 0.15)))
    )
    (fp_text user "${REFERENCE}" (at 0 0) (layer "F.Fab")
        (effects (font (size 0.25 0.25) (thickness 0.04)))
    )
    (fp_text user "License: Apache-2.0" (at -0.939 5.799) (layer "F.Fab") hide
        (effects (font (size 0.7 0.7) (thickness 0.15)) (justify left bottom))
    )
    (fp_text user "Author: Antmicro" (at -0.939 3.399) (layer "F.Fab") hide
        (effects (font (size 0.7 0.7) (thickness 0.15)) (justify left bottom))
    )
    (fp_rect (start -0.925 -0.47) (end 0.925 0.47)
      (stroke (width 0.05) (type default)) (fill none) (layer "F.CrtYd"))
    (fp_line (start -0.494 -0.25) (end 0.504 -0.25)
      (stroke (width 0.15) (type solid)) (layer "F.Fab"))
    (fp_line (start -0.494 0.248) (end -0.494 -0.25)
      (stroke (width 0.15) (type solid)) (layer "F.Fab"))
    (fp_line (start 0.504 -0.25) (end 0.504 0.248)
      (stroke (width 0.15) (type solid)) (layer "F.Fab"))
    (fp_line (start 0.504 0.248) (end -0.494 0.248)
      (stroke (width 0.15) (type solid)) (layer "F.Fab"))
    (pad "1" smd roundrect (at -0.48 0) (size 0.59 0.64) (layers "F.Cu" "F.Paste" "F.Mask") (roundrect_rratio 0.25)
      (net 1 "GND") (pintype "passive"))
    (pad "2" smd roundrect (at 0.48 0) (size 0.59 0.64) (layers "F.Cu" "F.Paste" "F.Mask") (roundrect_rratio 0.25)
      (net 357 "Net-(C120-Pad2)") (pintype "passive"))
  )
	(footprint "antmicro-footprints:C_0402_1005Metric" (layer "F.Cu")
    (at 74.05 85.1)
    (descr "Capacitor SMD 0402")
    (tags "capacitor SMD 0402")
    (property "Author" "Antmicro")
    (property "Dielectric" "")
    (property "License" "Apache-2.0")
    (property "MPN" "CC0402MRX5R5BB106")
    (property "Manufacturer" "YAGEO")
    (property "Public" "False")
    (property "Sheetfile" "power-supply.kicad_sch")
    (property "Sheetname" "Power supply")
    (property "Val" "10u")
    (property "Voltage" "")
    (property "ki_description" "SMD Multilayer Ceramic Capacitor, 10 µF, 6.3 V, 0402 [1005 Metric], ± 20%, X5R, CC Series")
    (property "ki_keywords" "0402, SMT, CAPACITOR, PASSIVE, MLCC, CERAMIC")
    (attr smd)
    (fp_text reference "C131" (at 1.48 -0.465 -90) (layer "F.SilkS")
        (effects (font (size 0.7 0.7) (thickness 0.127)))
    )
    (fp_text value "C_10u_0402" (at 0 1.17) (layer "F.Fab")
        (effects (font (size 1 1) (thickness 0.15)))
    )
    (fp_text user "License: Apache-2.0" (at -0.939 5.799) (layer "F.Fab") hide
        (effects (font (size 0.7 0.7) (thickness 0.15)) (justify left bottom))
    )
    (fp_text user "${REFERENCE}" (at 0 0) (layer "F.Fab")
        (effects (font (size 0.25 0.25) (thickness 0.04)))
    )
    (fp_text user "Author: Antmicro" (at -0.939 3.399) (layer "F.Fab") hide
        (effects (font (size 0.7 0.7) (thickness 0.15)) (justify left bottom))
    )
    (fp_rect (start -0.925 -0.47) (end 0.925 0.47)
      (stroke (width 0.05) (type default)) (fill none) (layer "F.CrtYd"))
    (fp_line (start -0.494 -0.25) (end 0.504 -0.25)
      (stroke (width 0.15) (type solid)) (layer "F.Fab"))
    (fp_line (start -0.494 0.248) (end -0.494 -0.25)
      (stroke (width 0.15) (type solid)) (layer "F.Fab"))
    (fp_line (start 0.504 -0.25) (end 0.504 0.248)
      (stroke (width 0.15) (type solid)) (layer "F.Fab"))
    (fp_line (start 0.504 0.248) (end -0.494 0.248)
      (stroke (width 0.15) (type solid)) (layer "F.Fab"))
    (pad "1" smd roundrect (at -0.48 0) (size 0.59 0.64) (layers "F.Cu" "F.Paste" "F.Mask") (roundrect_rratio 0.25)
      (net 1 "GND") (pintype "passive"))
    (pad "2" smd roundrect (at 0.48 0) (size 0.59 0.64) (layers "F.Cu" "F.Paste" "F.Mask") (roundrect_rratio 0.25)
      (net 358 "Net-(C121-Pad2)") (pintype "passive"))
  )
	(footprint "antmicro-footprints:C_0402_1005Metric" (layer "F.Cu")
    (at 86.05 85.1)
    (descr "Capacitor SMD 0402")
    (tags "capacitor SMD 0402")
    (property "Author" "Antmicro")
    (property "Dielectric" "")
    (property "License" "Apache-2.0")
    (property "MPN" "CC0402MRX5R5BB106")
    (property "Manufacturer" "YAGEO")
    (property "Public" "False")
    (property "Sheetfile" "power-supply.kicad_sch")
    (property "Sheetname" "Power supply")
    (property "Val" "10u")
    (property "Voltage" "")
    (property "ki_description" "SMD Multilayer Ceramic Capacitor, 10 µF, 6.3 V, 0402 [1005 Metric], ± 20%, X5R, CC Series")
    (property "ki_keywords" "0402, SMT, CAPACITOR, PASSIVE, MLCC, CERAMIC")
    (attr smd)
    (fp_text reference "C128" (at -1.35 0.1 90) (layer "F.SilkS")
        (effects (font (size 0.7 0.7) (thickness 0.127)))
    )
    (fp_text value "C_10u_0402" (at 0 1.17) (layer "F.Fab")
        (effects (font (size 1 1) (thickness 0.15)))
    )
    (fp_text user "${REFERENCE}" (at 0 0) (layer "F.Fab")
        (effects (font (size 0.25 0.25) (thickness 0.04)))
    )
    (fp_text user "Author: Antmicro" (at -0.939 3.399) (layer "F.Fab") hide
        (effects (font (size 0.7 0.7) (thickness 0.15)) (justify left bottom))
    )
    (fp_text user "License: Apache-2.0" (at -0.939 5.799) (layer "F.Fab") hide
        (effects (font (size 0.7 0.7) (thickness 0.15)) (justify left bottom))
    )
    (fp_rect (start -0.925 -0.47) (end 0.925 0.47)
      (stroke (width 0.05) (type default)) (fill none) (layer "F.CrtYd"))
    (fp_line (start -0.494 -0.25) (end 0.504 -0.25)
      (stroke (width 0.15) (type solid)) (layer "F.Fab"))
    (fp_line (start -0.494 0.248) (end -0.494 -0.25)
      (stroke (width 0.15) (type solid)) (layer "F.Fab"))
    (fp_line (start 0.504 -0.25) (end 0.504 0.248)
      (stroke (width 0.15) (type solid)) (layer "F.Fab"))
    (fp_line (start 0.504 0.248) (end -0.494 0.248)
      (stroke (width 0.15) (type solid)) (layer "F.Fab"))
    (pad "1" smd roundrect (at -0.48 0) (size 0.59 0.64) (layers "F.Cu" "F.Paste" "F.Mask") (roundrect_rratio 0.25)
      (net 1 "GND") (pintype "passive"))
    (pad "2" smd roundrect (at 0.48 0) (size 0.59 0.64) (layers "F.Cu" "F.Paste" "F.Mask") (roundrect_rratio 0.25)
      (net 355 "Net-(C118-Pad2)") (pintype "passive"))
  )
)
